(kicad_pcb
	(version 20260206)
	(generator "pcbnew")
	(generator_version "10.0")
	(general
		(thickness 1.6)
		(legacy_teardrops no)
	)
	(paper "A4")
	(title_block
		(title "01162023_DA0F0TEBIF0_F0T_Expander_BD_F_brd_V02_OCP.brd")
		(comment 1 "Grand Teton / footprints 8194-8203 of 9728")
	)
	(layers
		(0 "F.Cu" signal "TOP")
		(4 "In1.Cu" signal "GND")
		(6 "In2.Cu" signal "VCC")
		(8 "In3.Cu" signal "VCC1")
		(10 "In4.Cu" signal "GND1")
		(12 "In5.Cu" signal "IN1")
		(14 "In6.Cu" signal "GND2")
		(16 "In7.Cu" signal "IN2")
		(18 "In8.Cu" signal "GND3")
		(20 "In9.Cu" signal "IN3")
		(22 "In10.Cu" signal "GND4")
		(24 "In11.Cu" signal "IN4")
		(26 "In12.Cu" signal "GND5")
		(28 "In13.Cu" signal "IN5")
		(30 "In14.Cu" signal "GND6")
		(32 "In15.Cu" signal "IN6")
		(34 "In16.Cu" signal "GND7")
		(2 "B.Cu" signal "BOTTOM")
		(9 "F.Adhes" user "F.Adhesive")
		(11 "B.Adhes" user "B.Adhesive")
		(13 "F.Paste" user "Package Geometry/Pastemask Top")
		(15 "B.Paste" user "Package Geometry/Pastemask Bottom")
		(5 "F.SilkS" user "Ref Des/Silkscreen Top")
		(7 "B.SilkS" user "Ref Des/Silkscreen Bottom")
		(1 "F.Mask" user "Board Geometry/Soldermask Top")
		(3 "B.Mask" user "Board Geometry/Soldermask Bottom")
		(17 "Dwgs.User" user "User.Drawings")
		(19 "Cmts.User" user "User.Comments")
		(21 "Eco1.User" user "User.Eco1")
		(23 "Eco2.User" user "User.Eco2")
		(25 "Edge.Cuts" user "Board Geometry/Outline")
		(27 "Margin" user)
		(31 "F.CrtYd" user "Package Geometry/Place Bound Top")
		(29 "B.CrtYd" user "Package Geometry/Place Bound Bottom")
		(35 "F.Fab" user "Ref Des/Assembly Top")
		(33 "B.Fab" user "Ref Des/Assembly Bottom")
	)
	(footprint ""
		(layer "B.Cu")
		(at 340.493858 -221.98711 90)
		(property "Reference" "C2037"
			(at 0 0 90)
			(layer "B.SilkS")
			(hide yes)
			(effects
				(font
					(size 1.27 1.27)
				)
				(justify mirror)
			)
		)
		(property "Value" ""
			(at 0 0 90)
			(layer "B.Fab")
			(effects
				(font
					(size 1.27 1.27)
				)
				(justify mirror)
			)
		)
		(duplicate_pad_numbers_are_jumpers no)
		(fp_line
			(start 0.69215 -0.2921)
			(end -0.69215 -0.2921)
			(stroke
				(width 0.1524)
				(type default)
			)
			(layer "B.SilkS")
		)
		(fp_line
			(start -0.69215 -0.2921)
			(end -0.69215 0.2921)
			(stroke
				(width 0.1524)
				(type default)
			)
			(layer "B.SilkS")
		)
		(fp_line
			(start 0.69215 0.2921)
			(end 0.69215 -0.2921)
			(stroke
				(width 0.1524)
				(type default)
			)
			(layer "B.SilkS")
		)
		(fp_line
			(start -0.69215 0.2921)
			(end 0.69215 0.2921)
			(stroke
				(width 0.1524)
				(type default)
			)
			(layer "B.SilkS")
		)
		(fp_line
			(start 0.51435 -0.2794)
			(end -0.51435 -0.2794)
			(stroke
				(width 0.1)
				(type default)
			)
			(layer "B.Fab")
		)
		(fp_line
			(start -0.51435 -0.2794)
			(end -0.51435 0.2794)
			(stroke
				(width 0.1)
				(type default)
			)
			(layer "B.Fab")
		)
		(fp_line
			(start 0.51435 0.2794)
			(end 0.51435 -0.2794)
			(stroke
				(width 0.1)
				(type default)
			)
			(layer "B.Fab")
		)
		(fp_line
			(start -0.51435 0.2794)
			(end 0.51435 0.2794)
			(stroke
				(width 0.1)
				(type default)
			)
			(layer "B.Fab")
		)
		(pad "1" smd circle
			(at 0.40005 0 270)
			(size 0 0)
			(layers "B.Cu" "B.Mask" "B.Paste")
			(net "P3V3_FPGA_VCCIO0")
		)
		(pad "2" smd circle
			(at -0.40005 0 270)
			(size 0 0)
			(layers "B.Cu" "B.Mask" "B.Paste")
			(net "GND")
		)
		(zone
			(layer "B.Cu")
			(hatch none 0.5)
			(connect_pads
				(clearance 0)
			)
			(min_thickness 0.25)
			(keepout
				(tracks not_allowed)
				(vias allowed)
				(pads allowed)
				(copperpour not_allowed)
				(footprints allowed)
			)
			(placement
				(enabled no)
				(sheetname "")
			)
			(fill
				(thermal_gap 0.5)
				(thermal_bridge_width 0.5)
				(island_removal_mode 0)
			)
			(polygon
				(pts
					(xy 340.581488 -222.17761) (xy 340.639654 -222.08617) (xy 340.639654 -221.88678) (xy 340.581488 -221.79661)
					(xy 340.406228 -221.79661) (xy 340.347808 -221.88678) (xy 340.347808 -222.08617) (xy 340.405974 -222.17761)
				)
			)
		)
	)
	(footprint ""
		(layer "B.Cu")
		(at 186.200034 -290.674806 180)
		(property "Reference" "C3167"
			(at 0 0 0)
			(layer "B.SilkS")
			(hide yes)
			(effects
				(font
					(size 1.27 1.27)
				)
				(justify mirror)
			)
		)
		(property "Value" ""
			(at 0 0 0)
			(layer "B.Fab")
			(effects
				(font
					(size 1.27 1.27)
				)
				(justify mirror)
			)
		)
		(duplicate_pad_numbers_are_jumpers no)
		(fp_line
			(start 0.299974 0.150114)
			(end 0.299974 -0.150114)
			(stroke
				(width 0.1)
				(type default)
			)
			(layer "B.Fab")
		)
		(fp_line
			(start 0.299974 -0.150114)
			(end -0.299974 -0.150114)
			(stroke
				(width 0.1)
				(type default)
			)
			(layer "B.Fab")
		)
		(fp_line
			(start -0.299974 0.150114)
			(end 0.299974 0.150114)
			(stroke
				(width 0.1)
				(type default)
			)
			(layer "B.Fab")
		)
		(fp_line
			(start -0.299974 -0.150114)
			(end -0.299974 0.150114)
			(stroke
				(width 0.1)
				(type default)
			)
			(layer "B.Fab")
		)
		(pad "1" smd rect
			(at 0.2667 0)
			(size 0.3048 0.381)
			(layers "B.Cu" "B.Mask" "B.Paste")
			(net "P1V8_PEX")
		)
		(pad "2" smd rect
			(at -0.2667 0)
			(size 0.3048 0.381)
			(layers "B.Cu" "B.Mask" "B.Paste")
			(net "GND")
		)
	)
	(footprint ""
		(layer "B.Cu")
		(at 63.924942 -293.99992 -90)
		(property "Reference" "C1141"
			(at 0 0 90)
			(layer "B.SilkS")
			(hide yes)
			(effects
				(font
					(size 1.27 1.27)
				)
				(justify mirror)
			)
		)
		(property "Value" ""
			(at 0 0 90)
			(layer "B.Fab")
			(effects
				(font
					(size 1.27 1.27)
				)
				(justify mirror)
			)
		)
		(duplicate_pad_numbers_are_jumpers no)
		(fp_line
			(start -0.299974 0.150114)
			(end 0.299974 0.150114)
			(stroke
				(width 0.1)
				(type default)
			)
			(layer "B.Fab")
		)
		(fp_line
			(start 0.299974 0.150114)
			(end 0.299974 -0.150114)
			(stroke
				(width 0.1)
				(type default)
			)
			(layer "B.Fab")
		)
		(fp_line
			(start -0.299974 -0.150114)
			(end -0.299974 0.150114)
			(stroke
				(width 0.1)
				(type default)
			)
			(layer "B.Fab")
		)
		(fp_line
			(start 0.299974 -0.150114)
			(end -0.299974 -0.150114)
			(stroke
				(width 0.1)
				(type default)
			)
			(layer "B.Fab")
		)
		(pad "1" smd rect
			(at 0.2667 0 90)
			(size 0.3048 0.381)
			(layers "B.Cu" "B.Mask" "B.Paste")
			(net "P0V8_PEX0")
		)
		(pad "2" smd rect
			(at -0.2667 0 90)
			(size 0.3048 0.381)
			(layers "B.Cu" "B.Mask" "B.Paste")
			(net "GND")
		)
	)
	(footprint ""
		(layer "B.Cu")
		(at 288.049716 -292.099746 90)
		(property "Reference" "C1732"
			(at 0 0 90)
			(layer "B.SilkS")
			(hide yes)
			(effects
				(font
					(size 1.27 1.27)
				)
				(justify mirror)
			)
		)
		(property "Value" ""
			(at 0 0 90)
			(layer "B.Fab")
			(effects
				(font
					(size 1.27 1.27)
				)
				(justify mirror)
			)
		)
		(duplicate_pad_numbers_are_jumpers no)
		(fp_line
			(start 0.299974 -0.150114)
			(end -0.299974 -0.150114)
			(stroke
				(width 0.1)
				(type default)
			)
			(layer "B.Fab")
		)
		(fp_line
			(start -0.299974 -0.150114)
			(end -0.299974 0.150114)
			(stroke
				(width 0.1)
				(type default)
			)
			(layer "B.Fab")
		)
		(fp_line
			(start 0.299974 0.150114)
			(end 0.299974 -0.150114)
			(stroke
				(width 0.1)
				(type default)
			)
			(layer "B.Fab")
		)
		(fp_line
			(start -0.299974 0.150114)
			(end 0.299974 0.150114)
			(stroke
				(width 0.1)
				(type default)
			)
			(layer "B.Fab")
		)
		(pad "1" smd rect
			(at 0.2667 0 270)
			(size 0.3048 0.381)
			(layers "B.Cu" "B.Mask" "B.Paste")
			(net "P0V8_SERDES_VDDA_PEX2")
		)
		(pad "2" smd rect
			(at -0.2667 0 270)
			(size 0.3048 0.381)
			(layers "B.Cu" "B.Mask" "B.Paste")
			(net "GND")
		)
	)
	(footprint ""
		(layer "B.Cu")
		(at 314.165234 -443.028832 -90)
		(property "Reference" "J47"
			(at 2.4257 -5.635752 90)
			(unlocked yes)
			(layer "B.SilkS")
			(effects
				(font
					(size 0.7874 0.5842)
					(thickness 0.1524)
				)
				(justify mirror)
			)
		)
		(property "Value" ""
			(at 0 0 90)
			(layer "B.Fab")
			(effects
				(font
					(size 1.27 1.27)
				)
				(justify mirror)
			)
		)
		(duplicate_pad_numbers_are_jumpers no)
		(fp_line
			(start 0 4.011168)
			(end 3.330702 -4.771136)
			(stroke
				(width 0.1524)
				(type default)
			)
			(layer "B.SilkS")
		)
		(fp_line
			(start -3.330702 -4.771136)
			(end 0 4.011168)
			(stroke
				(width 0.1524)
				(type default)
			)
			(layer "B.SilkS")
		)
		(fp_line
			(start 3.330702 -4.771136)
			(end -3.330702 -4.771136)
			(stroke
				(width 0.1524)
				(type default)
			)
			(layer "B.SilkS")
		)
		(fp_line
			(start 0 4.011168)
			(end 3.330702 -4.771136)
			(stroke
				(width 0.1)
				(type default)
			)
			(layer "B.Fab")
		)
		(fp_line
			(start -3.330702 -4.771136)
			(end 0 4.011168)
			(stroke
				(width 0.1)
				(type default)
			)
			(layer "B.Fab")
		)
		(fp_line
			(start 3.330702 -4.771136)
			(end -3.330702 -4.771136)
			(stroke
				(width 0.1)
				(type default)
			)
			(layer "B.Fab")
		)
		(pad "1" thru_hole circle
			(at 0 0 90)
			(size 2.159 2.159)
			(drill 1.7018)
			(layers "*.Cu" "*.Mask")
			(remove_unused_layers no)
			(net "COUPON_GND1")
			(clearance 0.0254)
			(thermal_gap 0.0254)
		)
		(pad "2" thru_hole circle
			(at 1.27 -3.348736 90)
			(size 2.159 2.159)
			(drill 1.7018)
			(layers "*.Cu" "*.Mask")
			(remove_unused_layers no)
			(net "TDR_SE_50_OHM_IN1")
			(clearance 0.0254)
			(thermal_gap 0.0254)
		)
		(pad "3" thru_hole circle
			(at -1.27 -3.348736 90)
			(size 2.159 2.159)
			(drill 1.7018)
			(layers "*.Cu" "*.Mask")
			(remove_unused_layers no)
			(net "TDR_SE_50_OHM_IN1")
			(clearance 0.0254)
			(thermal_gap 0.0254)
		)
	)
	(footprint ""
		(layer "B.Cu")
		(at 351.155 -233.553 90)
		(property "Reference" "R3605"
			(at 0 0 90)
			(layer "B.SilkS")
			(hide yes)
			(effects
				(font
					(size 1.27 1.27)
				)
				(justify mirror)
			)
		)
		(property "Value" ""
			(at 0 0 90)
			(layer "B.Fab")
			(effects
				(font
					(size 1.27 1.27)
				)
				(justify mirror)
			)
		)
		(duplicate_pad_numbers_are_jumpers no)
		(fp_line
			(start 0.7874 -0.4064)
			(end -0.7874 -0.4064)
			(stroke
				(width 0.1524)
				(type default)
			)
			(layer "B.SilkS")
		)
		(fp_line
			(start -0.7874 -0.4064)
			(end -0.7874 0.4064)
			(stroke
				(width 0.1524)
				(type default)
			)
			(layer "B.SilkS")
		)
		(fp_line
			(start 0.7874 0.4064)
			(end 0.7874 -0.4064)
			(stroke
				(width 0.1524)
				(type default)
			)
			(layer "B.SilkS")
		)
		(fp_line
			(start -0.7874 0.4064)
			(end 0.7874 0.4064)
			(stroke
				(width 0.1524)
				(type default)
			)
			(layer "B.SilkS")
		)
		(fp_line
			(start 0.67945 -0.305054)
			(end 0.12065 -0.305054)
			(stroke
				(width 0.1)
				(type default)
			)
			(layer "B.Fab")
		)
		(fp_line
			(start 0.12065 -0.305054)
			(end 0.12065 -0.2794)
			(stroke
				(width 0.1)
				(type default)
			)
			(layer "B.Fab")
		)
		(fp_line
			(start -0.12065 -0.3048)
			(end -0.67945 -0.3048)
			(stroke
				(width 0.1)
				(type default)
			)
			(layer "B.Fab")
		)
		(fp_line
			(start -0.67945 -0.3048)
			(end -0.67945 0.3048)
			(stroke
				(width 0.1)
				(type default)
			)
			(layer "B.Fab")
		)
		(fp_line
			(start 0.12065 -0.2794)
			(end -0.12065 -0.2794)
			(stroke
				(width 0.1)
				(type default)
			)
			(layer "B.Fab")
		)
		(fp_line
			(start -0.12065 -0.2794)
			(end -0.12065 -0.3048)
			(stroke
				(width 0.1)
				(type default)
			)
			(layer "B.Fab")
		)
		(fp_line
			(start 0.12065 0.2794)
			(end 0.12065 0.3048)
			(stroke
				(width 0.1)
				(type default)
			)
			(layer "B.Fab")
		)
		(fp_line
			(start -0.120396 0.2794)
			(end 0.12065 0.2794)
			(stroke
				(width 0.1)
				(type default)
			)
			(layer "B.Fab")
		)
		(fp_line
			(start 0.67945 0.3048)
			(end 0.67945 -0.305054)
			(stroke
				(width 0.1)
				(type default)
			)
			(layer "B.Fab")
		)
		(fp_line
			(start 0.12065 0.3048)
			(end 0.67945 0.3048)
			(stroke
				(width 0.1)
				(type default)
			)
			(layer "B.Fab")
		)
		(fp_line
			(start -0.120396 0.3048)
			(end -0.120396 0.2794)
			(stroke
				(width 0.1)
				(type default)
			)
			(layer "B.Fab")
		)
		(fp_line
			(start -0.67945 0.3048)
			(end -0.120396 0.3048)
			(stroke
				(width 0.1)
				(type default)
			)
			(layer "B.Fab")
		)
		(pad "1" smd circle
			(at 0.40005 0 270)
			(size 0 0)
			(layers "B.Cu" "B.Mask" "B.Paste")
			(net "NIC0_CLK_EN_R_N")
		)
		(pad "2" smd circle
			(at -0.40005 0 270)
			(size 0 0)
			(layers "B.Cu" "B.Mask" "B.Paste")
			(net "NIC0_CLK_EN_N")
		)
	)
	(footprint ""
		(layer "B.Cu")
		(at 178.124866 -286.399732 90)
		(property "Reference" "C3132"
			(at 0 0 90)
			(layer "B.SilkS")
			(hide yes)
			(effects
				(font
					(size 1.27 1.27)
				)
				(justify mirror)
			)
		)
		(property "Value" ""
			(at 0 0 90)
			(layer "B.Fab")
			(effects
				(font
					(size 1.27 1.27)
				)
				(justify mirror)
			)
		)
		(duplicate_pad_numbers_are_jumpers no)
		(fp_line
			(start 0.299974 -0.150114)
			(end -0.299974 -0.150114)
			(stroke
				(width 0.1)
				(type default)
			)
			(layer "B.Fab")
		)
		(fp_line
			(start -0.299974 -0.150114)
			(end -0.299974 0.150114)
			(stroke
				(width 0.1)
				(type default)
			)
			(layer "B.Fab")
		)
		(fp_line
			(start 0.299974 0.150114)
			(end 0.299974 -0.150114)
			(stroke
				(width 0.1)
				(type default)
			)
			(layer "B.Fab")
		)
		(fp_line
			(start -0.299974 0.150114)
			(end 0.299974 0.150114)
			(stroke
				(width 0.1)
				(type default)
			)
			(layer "B.Fab")
		)
		(pad "1" smd rect
			(at 0.2667 0 270)
			(size 0.3048 0.381)
			(layers "B.Cu" "B.Mask" "B.Paste")
			(net "P1V25_SERDES_VDDPLL_PEX1")
		)
		(pad "2" smd rect
			(at -0.2667 0 270)
			(size 0.3048 0.381)
			(layers "B.Cu" "B.Mask" "B.Paste")
			(net "GND")
		)
	)
	(footprint ""
		(layer "B.Cu")
		(at 215.480392 -210.164426)
		(property "Reference" "R5890"
			(at 0 0 0)
			(layer "B.SilkS")
			(hide yes)
			(effects
				(font
					(size 1.27 1.27)
				)
				(justify mirror)
			)
		)
		(property "Value" ""
			(at 0 0 0)
			(layer "B.Fab")
			(effects
				(font
					(size 1.27 1.27)
				)
				(justify mirror)
			)
		)
		(duplicate_pad_numbers_are_jumpers no)
		(fp_line
			(start -0.7874 -0.4064)
			(end -0.7874 0.4064)
			(stroke
				(width 0.1524)
				(type default)
			)
			(layer "B.SilkS")
		)
		(fp_line
			(start -0.7874 0.4064)
			(end 0.7874 0.4064)
			(stroke
				(width 0.1524)
				(type default)
			)
			(layer "B.SilkS")
		)
		(fp_line
			(start 0.7874 -0.4064)
			(end -0.7874 -0.4064)
			(stroke
				(width 0.1524)
				(type default)
			)
			(layer "B.SilkS")
		)
		(fp_line
			(start 0.7874 0.4064)
			(end 0.7874 -0.4064)
			(stroke
				(width 0.1524)
				(type default)
			)
			(layer "B.SilkS")
		)
		(fp_line
			(start -0.67945 -0.3048)
			(end -0.67945 0.3048)
			(stroke
				(width 0.1)
				(type default)
			)
			(layer "B.Fab")
		)
		(fp_line
			(start -0.67945 0.3048)
			(end -0.120396 0.3048)
			(stroke
				(width 0.1)
				(type default)
			)
			(layer "B.Fab")
		)
		(fp_line
			(start -0.12065 -0.3048)
			(end -0.67945 -0.3048)
			(stroke
				(width 0.1)
				(type default)
			)
			(layer "B.Fab")
		)
		(fp_line
			(start -0.12065 -0.2794)
			(end -0.12065 -0.3048)
			(stroke
				(width 0.1)
				(type default)
			)
			(layer "B.Fab")
		)
		(fp_line
			(start -0.120396 0.2794)
			(end 0.12065 0.2794)
			(stroke
				(width 0.1)
				(type default)
			)
			(layer "B.Fab")
		)
		(fp_line
			(start -0.120396 0.3048)
			(end -0.120396 0.2794)
			(stroke
				(width 0.1)
				(type default)
			)
			(layer "B.Fab")
		)
		(fp_line
			(start 0.12065 -0.305054)
			(end 0.12065 -0.2794)
			(stroke
				(width 0.1)
				(type default)
			)
			(layer "B.Fab")
		)
		(fp_line
			(start 0.12065 -0.2794)
			(end -0.12065 -0.2794)
			(stroke
				(width 0.1)
				(type default)
			)
			(layer "B.Fab")
		)
		(fp_line
			(start 0.12065 0.2794)
			(end 0.12065 0.3048)
			(stroke
				(width 0.1)
				(type default)
			)
			(layer "B.Fab")
		)
		(fp_line
			(start 0.12065 0.3048)
			(end 0.67945 0.3048)
			(stroke
				(width 0.1)
				(type default)
			)
			(layer "B.Fab")
		)
		(fp_line
			(start 0.67945 -0.305054)
			(end 0.12065 -0.305054)
			(stroke
				(width 0.1)
				(type default)
			)
			(layer "B.Fab")
		)
		(fp_line
			(start 0.67945 0.3048)
			(end 0.67945 -0.305054)
			(stroke
				(width 0.1)
				(type default)
			)
			(layer "B.Fab")
		)
		(pad "1" smd circle
			(at 0.40005 0 180)
			(size 0 0)
			(layers "B.Cu" "B.Mask" "B.Paste")
			(net "FM_SYS_THROTTLE_R1")
		)
		(pad "2" smd circle
			(at -0.40005 0 180)
			(size 0 0)
			(layers "B.Cu" "B.Mask" "B.Paste")
			(net "FM_SYS_THROTTLE_R")
		)
	)
	(footprint ""
		(layer "B.Cu")
		(at 60.599828 -290.199826 90)
		(property "Reference" "C1221"
			(at 0 0 90)
			(layer "B.SilkS")
			(hide yes)
			(effects
				(font
					(size 1.27 1.27)
				)
				(justify mirror)
			)
		)
		(property "Value" ""
			(at 0 0 90)
			(layer "B.Fab")
			(effects
				(font
					(size 1.27 1.27)
				)
				(justify mirror)
			)
		)
		(duplicate_pad_numbers_are_jumpers no)
		(fp_line
			(start 0.299974 -0.150114)
			(end -0.299974 -0.150114)
			(stroke
				(width 0.1)
				(type default)
			)
			(layer "B.Fab")
		)
		(fp_line
			(start -0.299974 -0.150114)
			(end -0.299974 0.150114)
			(stroke
				(width 0.1)
				(type default)
			)
			(layer "B.Fab")
		)
		(fp_line
			(start 0.299974 0.150114)
			(end 0.299974 -0.150114)
			(stroke
				(width 0.1)
				(type default)
			)
			(layer "B.Fab")
		)
		(fp_line
			(start -0.299974 0.150114)
			(end 0.299974 0.150114)
			(stroke
				(width 0.1)
				(type default)
			)
			(layer "B.Fab")
		)
		(pad "1" smd rect
			(at 0.2667 0 270)
			(size 0.3048 0.381)
			(layers "B.Cu" "B.Mask" "B.Paste")
			(net "P0V8_SERDES_VDDA_PEX0")
		)
		(pad "2" smd rect
			(at -0.2667 0 270)
			(size 0.3048 0.381)
			(layers "B.Cu" "B.Mask" "B.Paste")
			(net "GND")
		)
	)
	(footprint ""
		(layer "B.Cu")
		(at 392.749786 -293.99992)
		(property "Reference" "C3509"
			(at 0 0 0)
			(layer "B.SilkS")
			(hide yes)
			(effects
				(font
					(size 1.27 1.27)
				)
				(justify mirror)
			)
		)
		(property "Value" ""
			(at 0 0 0)
			(layer "B.Fab")
			(effects
				(font
					(size 1.27 1.27)
				)
				(justify mirror)
			)
		)
		(duplicate_pad_numbers_are_jumpers no)
		(fp_line
			(start -0.299974 -0.150114)
			(end -0.299974 0.150114)
			(stroke
				(width 0.1)
				(type default)
			)
			(layer "B.Fab")
		)
		(fp_line
			(start -0.299974 0.150114)
			(end 0.299974 0.150114)
			(stroke
				(width 0.1)
				(type default)
			)
			(layer "B.Fab")
		)
		(fp_line
			(start 0.299974 -0.150114)
			(end -0.299974 -0.150114)
			(stroke
				(width 0.1)
				(type default)
			)
			(layer "B.Fab")
		)
		(fp_line
			(start 0.299974 0.150114)
			(end 0.299974 -0.150114)
			(stroke
				(width 0.1)
				(type default)
			)
			(layer "B.Fab")
		)
		(pad "1" smd rect
			(at 0.2667 0 180)
			(size 0.3048 0.381)
			(layers "B.Cu" "B.Mask" "B.Paste")
			(net "P1V8_PEX")
		)
		(pad "2" smd rect
			(at -0.2667 0 180)
			(size 0.3048 0.381)
			(layers "B.Cu" "B.Mask" "B.Paste")
			(net "GND")
		)
	)
)
